(kicad_pcb
	(version 20260206)
	(generator "pcbnew")
	(generator_version "10.0")
	(general
		(thickness 1.6)
		(legacy_teardrops no)
	)
	(paper "A4")
	(title_block
		(title "03242023_DA0F0TMBIJ0_F0T_Motherboard_J_brd_V01_OCP.brd")
		(comment 1 "Grand Teton / footprints 3947-3952 of 6105")
	)
	(layers
		(0 "F.Cu" signal "TOP")
		(4 "In1.Cu" signal "GND")
		(6 "In2.Cu" signal "IN1")
		(8 "In3.Cu" signal "GND1")
		(10 "In4.Cu" signal "IN2")
		(12 "In5.Cu" signal "GND2")
		(14 "In6.Cu" signal "IN3")
		(16 "In7.Cu" signal "GND3")
		(18 "In8.Cu" signal "VCC")
		(20 "In9.Cu" signal "VCC1")
		(22 "In10.Cu" signal "GND4")
		(24 "In11.Cu" signal "IN4")
		(26 "In12.Cu" signal "GND5")
		(28 "In13.Cu" signal "IN5")
		(30 "In14.Cu" signal "GND6")
		(32 "In15.Cu" signal "IN6")
		(34 "In16.Cu" signal "GND7")
		(2 "B.Cu" signal "BOTTOM")
		(9 "F.Adhes" user "F.Adhesive")
		(11 "B.Adhes" user "B.Adhesive")
		(13 "F.Paste" user "Package Geometry/Pastemask Top")
		(15 "B.Paste" user "Package Geometry/Pastemask Bottom")
		(5 "F.SilkS" user "Ref Des/Silkscreen Top")
		(7 "B.SilkS" user "Ref Des/Silkscreen Bottom")
		(1 "F.Mask" user "Board Geometry/Soldermask Top")
		(3 "B.Mask" user "Board Geometry/Soldermask Bottom")
		(17 "Dwgs.User" user "User.Drawings")
		(19 "Cmts.User" user "User.Comments")
		(21 "Eco1.User" user "User.Eco1")
		(23 "Eco2.User" user "User.Eco2")
		(25 "Edge.Cuts" user "Board Geometry/Outline")
		(27 "Margin" user)
		(31 "F.CrtYd" user "Package Geometry/Place Bound Top")
		(29 "B.CrtYd" user "Package Geometry/Place Bound Bottom")
		(35 "F.Fab" user "Ref Des/Assembly Top")
		(33 "B.Fab" user "Ref Des/Assembly Bottom")
	)
	(footprint ""
		(layer "F.Cu")
		(at 36.956238 -126.69774)
		(property "Reference" "C2450"
			(at 0 0 0)
			(layer "F.SilkS")
			(hide yes)
			(effects
				(font
					(size 1.27 1.27)
				)
			)
		)
		(property "Value" ""
			(at 0 0 0)
			(layer "F.Fab")
			(effects
				(font
					(size 1.27 1.27)
				)
			)
		)
		(duplicate_pad_numbers_are_jumpers no)
		(fp_line
			(start -0.7874 -0.4064)
			(end 0.7874 -0.4064)
			(stroke
				(width 0.1524)
				(type default)
			)
			(layer "F.SilkS")
		)
		(fp_line
			(start -0.7874 0.4064)
			(end -0.7874 -0.4064)
			(stroke
				(width 0.1524)
				(type default)
			)
			(layer "F.SilkS")
		)
		(fp_line
			(start 0.7874 -0.4064)
			(end 0.7874 0.4064)
			(stroke
				(width 0.1524)
				(type default)
			)
			(layer "F.SilkS")
		)
		(fp_line
			(start 0.7874 0.4064)
			(end -0.7874 0.4064)
			(stroke
				(width 0.1524)
				(type default)
			)
			(layer "F.SilkS")
		)
		(fp_line
			(start -0.67945 -0.305054)
			(end -0.12065 -0.305054)
			(stroke
				(width 0.1)
				(type default)
			)
			(layer "F.Fab")
		)
		(fp_line
			(start -0.67945 0.3048)
			(end -0.67945 -0.305054)
			(stroke
				(width 0.1)
				(type default)
			)
			(layer "F.Fab")
		)
		(fp_line
			(start -0.12065 -0.305054)
			(end -0.12065 -0.2794)
			(stroke
				(width 0.1)
				(type default)
			)
			(layer "F.Fab")
		)
		(fp_line
			(start -0.12065 -0.2794)
			(end 0.12065 -0.2794)
			(stroke
				(width 0.1)
				(type default)
			)
			(layer "F.Fab")
		)
		(fp_line
			(start -0.12065 0.2794)
			(end -0.12065 0.3048)
			(stroke
				(width 0.1)
				(type default)
			)
			(layer "F.Fab")
		)
		(fp_line
			(start -0.12065 0.3048)
			(end -0.67945 0.3048)
			(stroke
				(width 0.1)
				(type default)
			)
			(layer "F.Fab")
		)
		(fp_line
			(start 0.120396 0.2794)
			(end -0.12065 0.2794)
			(stroke
				(width 0.1)
				(type default)
			)
			(layer "F.Fab")
		)
		(fp_line
			(start 0.120396 0.3048)
			(end 0.120396 0.2794)
			(stroke
				(width 0.1)
				(type default)
			)
			(layer "F.Fab")
		)
		(fp_line
			(start 0.12065 -0.3048)
			(end 0.67945 -0.3048)
			(stroke
				(width 0.1)
				(type default)
			)
			(layer "F.Fab")
		)
		(fp_line
			(start 0.12065 -0.2794)
			(end 0.12065 -0.3048)
			(stroke
				(width 0.1)
				(type default)
			)
			(layer "F.Fab")
		)
		(fp_line
			(start 0.67945 -0.3048)
			(end 0.67945 0.3048)
			(stroke
				(width 0.1)
				(type default)
			)
			(layer "F.Fab")
		)
		(fp_line
			(start 0.67945 0.3048)
			(end 0.120396 0.3048)
			(stroke
				(width 0.1)
				(type default)
			)
			(layer "F.Fab")
		)
		(pad "1" smd circle
			(at -0.40005 0)
			(size 0 0)
			(layers "F.Cu" "F.Mask" "F.Paste")
			(net "PWRGD_PVCCINFAON_CPU1_R")
		)
		(pad "2" smd circle
			(at 0.40005 0)
			(size 0 0)
			(layers "F.Cu" "F.Mask" "F.Paste")
			(net "GND")
		)
	)
	(footprint ""
		(layer "F.Cu")
		(at 294.045894 -412.07436)
		(property "Reference" "R4690"
			(at 0 0 0)
			(layer "F.SilkS")
			(hide yes)
			(effects
				(font
					(size 1.27 1.27)
				)
			)
		)
		(property "Value" ""
			(at 0 0 0)
			(layer "F.Fab")
			(effects
				(font
					(size 1.27 1.27)
				)
			)
		)
		(duplicate_pad_numbers_are_jumpers no)
		(fp_line
			(start -0.7874 -0.4064)
			(end 0.7874 -0.4064)
			(stroke
				(width 0.1524)
				(type default)
			)
			(layer "F.SilkS")
		)
		(fp_line
			(start -0.7874 0.4064)
			(end -0.7874 -0.4064)
			(stroke
				(width 0.1524)
				(type default)
			)
			(layer "F.SilkS")
		)
		(fp_line
			(start 0.7874 -0.4064)
			(end 0.7874 0.4064)
			(stroke
				(width 0.1524)
				(type default)
			)
			(layer "F.SilkS")
		)
		(fp_line
			(start 0.7874 0.4064)
			(end -0.7874 0.4064)
			(stroke
				(width 0.1524)
				(type default)
			)
			(layer "F.SilkS")
		)
		(fp_line
			(start -0.67945 -0.305054)
			(end -0.12065 -0.305054)
			(stroke
				(width 0.1)
				(type default)
			)
			(layer "F.Fab")
		)
		(fp_line
			(start -0.67945 0.3048)
			(end -0.67945 -0.305054)
			(stroke
				(width 0.1)
				(type default)
			)
			(layer "F.Fab")
		)
		(fp_line
			(start -0.12065 -0.305054)
			(end -0.12065 -0.2794)
			(stroke
				(width 0.1)
				(type default)
			)
			(layer "F.Fab")
		)
		(fp_line
			(start -0.12065 -0.2794)
			(end 0.12065 -0.2794)
			(stroke
				(width 0.1)
				(type default)
			)
			(layer "F.Fab")
		)
		(fp_line
			(start -0.12065 0.2794)
			(end -0.12065 0.3048)
			(stroke
				(width 0.1)
				(type default)
			)
			(layer "F.Fab")
		)
		(fp_line
			(start -0.12065 0.3048)
			(end -0.67945 0.3048)
			(stroke
				(width 0.1)
				(type default)
			)
			(layer "F.Fab")
		)
		(fp_line
			(start 0.120396 0.2794)
			(end -0.12065 0.2794)
			(stroke
				(width 0.1)
				(type default)
			)
			(layer "F.Fab")
		)
		(fp_line
			(start 0.120396 0.3048)
			(end 0.120396 0.2794)
			(stroke
				(width 0.1)
				(type default)
			)
			(layer "F.Fab")
		)
		(fp_line
			(start 0.12065 -0.3048)
			(end 0.67945 -0.3048)
			(stroke
				(width 0.1)
				(type default)
			)
			(layer "F.Fab")
		)
		(fp_line
			(start 0.12065 -0.2794)
			(end 0.12065 -0.3048)
			(stroke
				(width 0.1)
				(type default)
			)
			(layer "F.Fab")
		)
		(fp_line
			(start 0.67945 -0.3048)
			(end 0.67945 0.3048)
			(stroke
				(width 0.1)
				(type default)
			)
			(layer "F.Fab")
		)
		(fp_line
			(start 0.67945 0.3048)
			(end 0.120396 0.3048)
			(stroke
				(width 0.1)
				(type default)
			)
			(layer "F.Fab")
		)
		(pad "1" smd circle
			(at -0.40005 0)
			(size 0 0)
			(layers "F.Cu" "F.Mask" "F.Paste")
			(net "SMB_LM75_0_3V3AUX_SDA")
		)
		(pad "2" smd circle
			(at 0.40005 0)
			(size 0 0)
			(layers "F.Cu" "F.Mask" "F.Paste")
			(net "SMB_HSC_TYPE_ADC_SDA")
		)
	)
	(footprint ""
		(layer "F.Cu")
		(at 392.363198 -161.07791)
		(property "Reference" "R971"
			(at 0 0 0)
			(layer "F.SilkS")
			(hide yes)
			(effects
				(font
					(size 1.27 1.27)
				)
			)
		)
		(property "Value" ""
			(at 0 0 0)
			(layer "F.Fab")
			(effects
				(font
					(size 1.27 1.27)
				)
			)
		)
		(duplicate_pad_numbers_are_jumpers no)
		(fp_line
			(start -0.7874 -0.4064)
			(end 0.7874 -0.4064)
			(stroke
				(width 0.1524)
				(type default)
			)
			(layer "F.SilkS")
		)
		(fp_line
			(start -0.7874 0.4064)
			(end -0.7874 -0.4064)
			(stroke
				(width 0.1524)
				(type default)
			)
			(layer "F.SilkS")
		)
		(fp_line
			(start 0.7874 -0.4064)
			(end 0.7874 0.4064)
			(stroke
				(width 0.1524)
				(type default)
			)
			(layer "F.SilkS")
		)
		(fp_line
			(start 0.7874 0.4064)
			(end -0.7874 0.4064)
			(stroke
				(width 0.1524)
				(type default)
			)
			(layer "F.SilkS")
		)
		(fp_line
			(start -0.67945 -0.305054)
			(end -0.12065 -0.305054)
			(stroke
				(width 0.1)
				(type default)
			)
			(layer "F.Fab")
		)
		(fp_line
			(start -0.67945 0.3048)
			(end -0.67945 -0.305054)
			(stroke
				(width 0.1)
				(type default)
			)
			(layer "F.Fab")
		)
		(fp_line
			(start -0.12065 -0.305054)
			(end -0.12065 -0.2794)
			(stroke
				(width 0.1)
				(type default)
			)
			(layer "F.Fab")
		)
		(fp_line
			(start -0.12065 -0.2794)
			(end 0.12065 -0.2794)
			(stroke
				(width 0.1)
				(type default)
			)
			(layer "F.Fab")
		)
		(fp_line
			(start -0.12065 0.2794)
			(end -0.12065 0.3048)
			(stroke
				(width 0.1)
				(type default)
			)
			(layer "F.Fab")
		)
		(fp_line
			(start -0.12065 0.3048)
			(end -0.67945 0.3048)
			(stroke
				(width 0.1)
				(type default)
			)
			(layer "F.Fab")
		)
		(fp_line
			(start 0.120396 0.2794)
			(end -0.12065 0.2794)
			(stroke
				(width 0.1)
				(type default)
			)
			(layer "F.Fab")
		)
		(fp_line
			(start 0.120396 0.3048)
			(end 0.120396 0.2794)
			(stroke
				(width 0.1)
				(type default)
			)
			(layer "F.Fab")
		)
		(fp_line
			(start 0.12065 -0.3048)
			(end 0.67945 -0.3048)
			(stroke
				(width 0.1)
				(type default)
			)
			(layer "F.Fab")
		)
		(fp_line
			(start 0.12065 -0.2794)
			(end 0.12065 -0.3048)
			(stroke
				(width 0.1)
				(type default)
			)
			(layer "F.Fab")
		)
		(fp_line
			(start 0.67945 -0.3048)
			(end 0.67945 0.3048)
			(stroke
				(width 0.1)
				(type default)
			)
			(layer "F.Fab")
		)
		(fp_line
			(start 0.67945 0.3048)
			(end 0.120396 0.3048)
			(stroke
				(width 0.1)
				(type default)
			)
			(layer "F.Fab")
		)
		(pad "1" smd circle
			(at -0.40005 0)
			(size 0 0)
			(layers "F.Cu" "F.Mask" "F.Paste")
			(net "PVNN_TERM_CPU0")
		)
		(pad "2" smd circle
			(at 0.40005 0)
			(size 0 0)
			(layers "F.Cu" "F.Mask" "F.Paste")
			(net "SMB_S3M_CPU0_R_SDA")
		)
	)
	(footprint ""
		(layer "F.Cu")
		(at 228.125782 -65.08496 180)
		(property "Reference" "PD113"
			(at 4.123944 -2.386076 0)
			(unlocked yes)
			(layer "F.SilkS")
			(effects
				(font
					(size 0.7874 0.5842)
					(thickness 0.1524)
				)
				(justify left)
			)
		)
		(property "Value" ""
			(at 0 0 180)
			(layer "F.Fab")
			(effects
				(font
					(size 1.27 1.27)
				)
			)
		)
		(duplicate_pad_numbers_are_jumpers no)
		(fp_line
			(start 4.107942 1.459992)
			(end -3.400044 1.459992)
			(stroke
				(width 0.1524)
				(type default)
			)
			(layer "F.SilkS")
		)
		(fp_line
			(start 4.107942 -1.459992)
			(end 4.107942 1.459992)
			(stroke
				(width 0.1524)
				(type default)
			)
			(layer "F.SilkS")
		)
		(fp_line
			(start -3.400044 1.459992)
			(end -3.400044 -1.459992)
			(stroke
				(width 0.1524)
				(type default)
			)
			(layer "F.SilkS")
		)
		(fp_line
			(start -3.400044 -1.459992)
			(end 4.107942 -1.459992)
			(stroke
				(width 0.1524)
				(type default)
			)
			(layer "F.SilkS")
		)
		(fp_rect
			(start 4.107942 -1.459992)
			(end 3.308096 1.459992)
			(stroke
				(width 0)
				(type default)
			)
			(fill yes)
			(layer "F.SilkS")
		)
		(fp_line
			(start 2.29997 1.459992)
			(end -2.29997 1.459992)
			(stroke
				(width 0.1)
				(type default)
			)
			(layer "F.Fab")
		)
		(fp_line
			(start 2.29997 -1.459992)
			(end 2.29997 1.459992)
			(stroke
				(width 0.1)
				(type default)
			)
			(layer "F.Fab")
		)
		(fp_line
			(start -2.29997 1.459992)
			(end -2.29997 -1.459992)
			(stroke
				(width 0.1)
				(type default)
			)
			(layer "F.Fab")
		)
		(fp_line
			(start -2.29997 -1.459992)
			(end 2.29997 -1.459992)
			(stroke
				(width 0.1)
				(type default)
			)
			(layer "F.Fab")
		)
		(fp_text user "-"
			(at 5.4102 0.29845 0)
			(unlocked yes)
			(layer "F.SilkS")
			(effects
				(font
					(size 1.905 1.4224)
					(thickness 0.1524)
				)
				(justify left)
			)
		)
		(fp_text user "+"
			(at -4.7752 -0.12065 180)
			(unlocked yes)
			(layer "F.SilkS")
			(effects
				(font
					(size 1.905 1.4224)
					(thickness 0.1524)
				)
				(justify left)
			)
		)
		(fp_text user "-"
			(at 5.4102 0.29845 0)
			(unlocked yes)
			(layer "F.Fab")
			(effects
				(font
					(size 1.905 1.4224)
					(thickness 0.1524)
				)
				(justify left)
			)
		)
		(fp_text user "+"
			(at -4.7752 -0.12065 180)
			(unlocked yes)
			(layer "F.Fab")
			(effects
				(font
					(size 1.905 1.4224)
					(thickness 0.1524)
				)
				(justify left)
			)
		)
		(pad "A" smd rect
			(at -1.999996 0 270)
			(size 1.7018 2.5146)
			(layers "F.Cu" "F.Mask" "F.Paste")
			(net "GND")
		)
		(pad "C" smd rect
			(at 1.999996 0 270)
			(size 1.7018 2.5146)
			(layers "F.Cu" "F.Mask" "F.Paste")
			(net "P3V3_E1S_0_R")
		)
	)
	(footprint ""
		(layer "F.Cu")
		(at 119.508016 -241.97691 -90)
		(property "Reference" "C269"
			(at 0 0 270)
			(layer "F.SilkS")
			(hide yes)
			(effects
				(font
					(size 1.27 1.27)
				)
			)
		)
		(property "Value" ""
			(at 0 0 270)
			(layer "F.Fab")
			(effects
				(font
					(size 1.27 1.27)
				)
			)
		)
		(duplicate_pad_numbers_are_jumpers no)
		(fp_line
			(start -0.7874 0.4064)
			(end -0.7874 -0.4064)
			(stroke
				(width 0.1524)
				(type default)
			)
			(layer "F.SilkS")
		)
		(fp_line
			(start 0.7874 0.4064)
			(end -0.7874 0.4064)
			(stroke
				(width 0.1524)
				(type default)
			)
			(layer "F.SilkS")
		)
		(fp_line
			(start -0.7874 -0.4064)
			(end 0.7874 -0.4064)
			(stroke
				(width 0.1524)
				(type default)
			)
			(layer "F.SilkS")
		)
		(fp_line
			(start 0.7874 -0.4064)
			(end 0.7874 0.4064)
			(stroke
				(width 0.1524)
				(type default)
			)
			(layer "F.SilkS")
		)
		(fp_line
			(start -0.67945 0.3048)
			(end -0.67945 -0.305054)
			(stroke
				(width 0.1)
				(type default)
			)
			(layer "F.Fab")
		)
		(fp_line
			(start -0.12065 0.3048)
			(end -0.67945 0.3048)
			(stroke
				(width 0.1)
				(type default)
			)
			(layer "F.Fab")
		)
		(fp_line
			(start 0.120396 0.3048)
			(end 0.120396 0.2794)
			(stroke
				(width 0.1)
				(type default)
			)
			(layer "F.Fab")
		)
		(fp_line
			(start 0.67945 0.3048)
			(end 0.120396 0.3048)
			(stroke
				(width 0.1)
				(type default)
			)
			(layer "F.Fab")
		)
		(fp_line
			(start -0.12065 0.2794)
			(end -0.12065 0.3048)
			(stroke
				(width 0.1)
				(type default)
			)
			(layer "F.Fab")
		)
		(fp_line
			(start 0.120396 0.2794)
			(end -0.12065 0.2794)
			(stroke
				(width 0.1)
				(type default)
			)
			(layer "F.Fab")
		)
		(fp_line
			(start -0.12065 -0.2794)
			(end 0.12065 -0.2794)
			(stroke
				(width 0.1)
				(type default)
			)
			(layer "F.Fab")
		)
		(fp_line
			(start 0.12065 -0.2794)
			(end 0.12065 -0.3048)
			(stroke
				(width 0.1)
				(type default)
			)
			(layer "F.Fab")
		)
		(fp_line
			(start 0.12065 -0.3048)
			(end 0.67945 -0.3048)
			(stroke
				(width 0.1)
				(type default)
			)
			(layer "F.Fab")
		)
		(fp_line
			(start 0.67945 -0.3048)
			(end 0.67945 0.3048)
			(stroke
				(width 0.1)
				(type default)
			)
			(layer "F.Fab")
		)
		(fp_line
			(start -0.67945 -0.305054)
			(end -0.12065 -0.305054)
			(stroke
				(width 0.1)
				(type default)
			)
			(layer "F.Fab")
		)
		(fp_line
			(start -0.12065 -0.305054)
			(end -0.12065 -0.2794)
			(stroke
				(width 0.1)
				(type default)
			)
			(layer "F.Fab")
		)
		(pad "1" smd circle
			(at -0.40005 0 270)
			(size 0 0)
			(layers "F.Cu" "F.Mask" "F.Paste")
			(net "PVCCIN_CPU1")
		)
		(pad "2" smd circle
			(at 0.40005 0 270)
			(size 0 0)
			(layers "F.Cu" "F.Mask" "F.Paste")
			(net "GND")
		)
	)
	(footprint ""
		(layer "F.Cu")
		(at 27.628596 -389.304276 180)
		(property "Reference" "R3286"
			(at 0 0 180)
			(layer "F.SilkS")
			(hide yes)
			(effects
				(font
					(size 1.27 1.27)
				)
			)
		)
		(property "Value" ""
			(at 0 0 180)
			(layer "F.Fab")
			(effects
				(font
					(size 1.27 1.27)
				)
			)
		)
		(duplicate_pad_numbers_are_jumpers no)
		(fp_line
			(start 0.7874 0.4064)
			(end -0.7874 0.4064)
			(stroke
				(width 0.1524)
				(type default)
			)
			(layer "F.SilkS")
		)
		(fp_line
			(start 0.7874 -0.4064)
			(end 0.7874 0.4064)
			(stroke
				(width 0.1524)
				(type default)
			)
			(layer "F.SilkS")
		)
		(fp_line
			(start -0.7874 0.4064)
			(end -0.7874 -0.4064)
			(stroke
				(width 0.1524)
				(type default)
			)
			(layer "F.SilkS")
		)
		(fp_line
			(start -0.7874 -0.4064)
			(end 0.7874 -0.4064)
			(stroke
				(width 0.1524)
				(type default)
			)
			(layer "F.SilkS")
		)
		(fp_line
			(start 0.67945 0.3048)
			(end 0.120396 0.3048)
			(stroke
				(width 0.1)
				(type default)
			)
			(layer "F.Fab")
		)
		(fp_line
			(start 0.67945 -0.3048)
			(end 0.67945 0.3048)
			(stroke
				(width 0.1)
				(type default)
			)
			(layer "F.Fab")
		)
		(fp_line
			(start 0.12065 -0.2794)
			(end 0.12065 -0.3048)
			(stroke
				(width 0.1)
				(type default)
			)
			(layer "F.Fab")
		)
		(fp_line
			(start 0.12065 -0.3048)
			(end 0.67945 -0.3048)
			(stroke
				(width 0.1)
				(type default)
			)
			(layer "F.Fab")
		)
		(fp_line
			(start 0.120396 0.3048)
			(end 0.120396 0.2794)
			(stroke
				(width 0.1)
				(type default)
			)
			(layer "F.Fab")
		)
		(fp_line
			(start 0.120396 0.2794)
			(end -0.12065 0.2794)
			(stroke
				(width 0.1)
				(type default)
			)
			(layer "F.Fab")
		)
		(fp_line
			(start -0.12065 0.3048)
			(end -0.67945 0.3048)
			(stroke
				(width 0.1)
				(type default)
			)
			(layer "F.Fab")
		)
		(fp_line
			(start -0.12065 0.2794)
			(end -0.12065 0.3048)
			(stroke
				(width 0.1)
				(type default)
			)
			(layer "F.Fab")
		)
		(fp_line
			(start -0.12065 -0.2794)
			(end 0.12065 -0.2794)
			(stroke
				(width 0.1)
				(type default)
			)
			(layer "F.Fab")
		)
		(fp_line
			(start -0.12065 -0.305054)
			(end -0.12065 -0.2794)
			(stroke
				(width 0.1)
				(type default)
			)
			(layer "F.Fab")
		)
		(fp_line
			(start -0.67945 0.3048)
			(end -0.67945 -0.305054)
			(stroke
				(width 0.1)
				(type default)
			)
			(layer "F.Fab")
		)
		(fp_line
			(start -0.67945 -0.305054)
			(end -0.12065 -0.305054)
			(stroke
				(width 0.1)
				(type default)
			)
			(layer "F.Fab")
		)
		(pad "1" smd circle
			(at -0.40005 0 180)
			(size 0 0)
			(layers "F.Cu" "F.Mask" "F.Paste")
			(net "P3V3_AUX")
		)
		(pad "2" smd circle
			(at 0.40005 0 180)
			(size 0 0)
			(layers "F.Cu" "F.Mask" "F.Paste")
			(net "FM_P2E_SWB")
		)
	)
)
